(kicad_pcb
	(version 20260206)
	(generator "pcbnew")
	(generator_version "10.0")
	(general
		(thickness 1.6)
		(legacy_teardrops no)
	)
	(paper "A4")
	(title_block
		(title "12092022_DA0F0TMDCD0_F0T_Management_Board_D_brd_V3_OCP.brd")
		(comment 1 "Grand Teton / footprints 1208-1213 of 1440")
	)
	(layers
		(0 "F.Cu" signal "TOP")
		(4 "In1.Cu" signal "GND")
		(6 "In2.Cu" signal "IN1")
		(8 "In3.Cu" signal "GND1")
		(10 "In4.Cu" signal "IN2")
		(12 "In5.Cu" signal "VCC")
		(14 "In6.Cu" signal "VCC1")
		(16 "In7.Cu" signal "IN3")
		(18 "In8.Cu" signal "GND2")
		(20 "In9.Cu" signal "IN4")
		(22 "In10.Cu" signal "GND3")
		(2 "B.Cu" signal "BOTTOM")
		(9 "F.Adhes" user "F.Adhesive")
		(11 "B.Adhes" user "B.Adhesive")
		(13 "F.Paste" user "Package Geometry/Pastemask Top")
		(15 "B.Paste" user "Package Geometry/Pastemask Bottom")
		(5 "F.SilkS" user "Ref Des/Silkscreen Top")
		(7 "B.SilkS" user "Ref Des/Silkscreen Bottom")
		(1 "F.Mask" user "Board Geometry/Soldermask Top")
		(3 "B.Mask" user "Board Geometry/Soldermask Bottom")
		(17 "Dwgs.User" user "User.Drawings")
		(19 "Cmts.User" user "User.Comments")
		(21 "Eco1.User" user "User.Eco1")
		(23 "Eco2.User" user "User.Eco2")
		(25 "Edge.Cuts" user "Board Geometry/Outline")
		(27 "Margin" user)
		(31 "F.CrtYd" user "Package Geometry/Place Bound Top")
		(29 "B.CrtYd" user "Package Geometry/Place Bound Bottom")
		(35 "F.Fab" user "Ref Des/Assembly Top")
		(33 "B.Fab" user "Ref Des/Assembly Bottom")
	)
	(footprint ""
		(layer "B.Cu")
		(at 39.647114 -61.627766)
		(property "Reference" "R804"
			(at 0 0 0)
			(layer "B.SilkS")
			(hide yes)
			(effects
				(font
					(size 1.27 1.27)
				)
				(justify mirror)
			)
		)
		(property "Value" ""
			(at 0 0 0)
			(layer "B.Fab")
			(effects
				(font
					(size 1.27 1.27)
				)
				(justify mirror)
			)
		)
		(duplicate_pad_numbers_are_jumpers no)
		(fp_line
			(start -0.7874 -0.4064)
			(end -0.7874 0.4064)
			(stroke
				(width 0.1524)
				(type default)
			)
			(layer "B.SilkS")
		)
		(fp_line
			(start -0.7874 0.4064)
			(end 0.7874 0.4064)
			(stroke
				(width 0.1524)
				(type default)
			)
			(layer "B.SilkS")
		)
		(fp_line
			(start 0.7874 -0.4064)
			(end -0.7874 -0.4064)
			(stroke
				(width 0.1524)
				(type default)
			)
			(layer "B.SilkS")
		)
		(fp_line
			(start 0.7874 0.4064)
			(end 0.7874 -0.4064)
			(stroke
				(width 0.1524)
				(type default)
			)
			(layer "B.SilkS")
		)
		(fp_line
			(start -0.67945 -0.3048)
			(end -0.67945 0.3048)
			(stroke
				(width 0.1)
				(type default)
			)
			(layer "B.Fab")
		)
		(fp_line
			(start -0.67945 0.3048)
			(end -0.120396 0.3048)
			(stroke
				(width 0.1)
				(type default)
			)
			(layer "B.Fab")
		)
		(fp_line
			(start -0.12065 -0.3048)
			(end -0.67945 -0.3048)
			(stroke
				(width 0.1)
				(type default)
			)
			(layer "B.Fab")
		)
		(fp_line
			(start -0.12065 -0.2794)
			(end -0.12065 -0.3048)
			(stroke
				(width 0.1)
				(type default)
			)
			(layer "B.Fab")
		)
		(fp_line
			(start -0.120396 0.2794)
			(end 0.12065 0.2794)
			(stroke
				(width 0.1)
				(type default)
			)
			(layer "B.Fab")
		)
		(fp_line
			(start -0.120396 0.3048)
			(end -0.120396 0.2794)
			(stroke
				(width 0.1)
				(type default)
			)
			(layer "B.Fab")
		)
		(fp_line
			(start 0.12065 -0.305054)
			(end 0.12065 -0.2794)
			(stroke
				(width 0.1)
				(type default)
			)
			(layer "B.Fab")
		)
		(fp_line
			(start 0.12065 -0.2794)
			(end -0.12065 -0.2794)
			(stroke
				(width 0.1)
				(type default)
			)
			(layer "B.Fab")
		)
		(fp_line
			(start 0.12065 0.2794)
			(end 0.12065 0.3048)
			(stroke
				(width 0.1)
				(type default)
			)
			(layer "B.Fab")
		)
		(fp_line
			(start 0.12065 0.3048)
			(end 0.67945 0.3048)
			(stroke
				(width 0.1)
				(type default)
			)
			(layer "B.Fab")
		)
		(fp_line
			(start 0.67945 -0.305054)
			(end 0.12065 -0.305054)
			(stroke
				(width 0.1)
				(type default)
			)
			(layer "B.Fab")
		)
		(fp_line
			(start 0.67945 0.3048)
			(end 0.67945 -0.305054)
			(stroke
				(width 0.1)
				(type default)
			)
			(layer "B.Fab")
		)
		(pad "1" smd circle
			(at 0.40005 0 180)
			(size 0 0)
			(layers "B.Cu" "B.Mask" "B.Paste")
			(net "SYS_BMC_PWRBTN_R1_N")
		)
		(pad "2" smd circle
			(at -0.40005 0 180)
			(size 0 0)
			(layers "B.Cu" "B.Mask" "B.Paste")
			(net "SYS_BMC_PWRBTN_R_N")
		)
	)
	(footprint ""
		(layer "B.Cu")
		(at 25.019 -91.44)
		(property "Reference" "R305"
			(at 0 0 0)
			(layer "B.SilkS")
			(hide yes)
			(effects
				(font
					(size 1.27 1.27)
				)
				(justify mirror)
			)
		)
		(property "Value" ""
			(at 0 0 0)
			(layer "B.Fab")
			(effects
				(font
					(size 1.27 1.27)
				)
				(justify mirror)
			)
		)
		(duplicate_pad_numbers_are_jumpers no)
		(fp_line
			(start -0.7874 -0.4064)
			(end -0.7874 0.4064)
			(stroke
				(width 0.1524)
				(type default)
			)
			(layer "B.SilkS")
		)
		(fp_line
			(start -0.7874 0.4064)
			(end 0.7874 0.4064)
			(stroke
				(width 0.1524)
				(type default)
			)
			(layer "B.SilkS")
		)
		(fp_line
			(start 0.7874 -0.4064)
			(end -0.7874 -0.4064)
			(stroke
				(width 0.1524)
				(type default)
			)
			(layer "B.SilkS")
		)
		(fp_line
			(start 0.7874 0.4064)
			(end 0.7874 -0.4064)
			(stroke
				(width 0.1524)
				(type default)
			)
			(layer "B.SilkS")
		)
		(fp_line
			(start -0.67945 -0.3048)
			(end -0.67945 0.3048)
			(stroke
				(width 0.1)
				(type default)
			)
			(layer "B.Fab")
		)
		(fp_line
			(start -0.67945 0.3048)
			(end -0.120396 0.3048)
			(stroke
				(width 0.1)
				(type default)
			)
			(layer "B.Fab")
		)
		(fp_line
			(start -0.12065 -0.3048)
			(end -0.67945 -0.3048)
			(stroke
				(width 0.1)
				(type default)
			)
			(layer "B.Fab")
		)
		(fp_line
			(start -0.12065 -0.2794)
			(end -0.12065 -0.3048)
			(stroke
				(width 0.1)
				(type default)
			)
			(layer "B.Fab")
		)
		(fp_line
			(start -0.120396 0.2794)
			(end 0.12065 0.2794)
			(stroke
				(width 0.1)
				(type default)
			)
			(layer "B.Fab")
		)
		(fp_line
			(start -0.120396 0.3048)
			(end -0.120396 0.2794)
			(stroke
				(width 0.1)
				(type default)
			)
			(layer "B.Fab")
		)
		(fp_line
			(start 0.12065 -0.305054)
			(end 0.12065 -0.2794)
			(stroke
				(width 0.1)
				(type default)
			)
			(layer "B.Fab")
		)
		(fp_line
			(start 0.12065 -0.2794)
			(end -0.12065 -0.2794)
			(stroke
				(width 0.1)
				(type default)
			)
			(layer "B.Fab")
		)
		(fp_line
			(start 0.12065 0.2794)
			(end 0.12065 0.3048)
			(stroke
				(width 0.1)
				(type default)
			)
			(layer "B.Fab")
		)
		(fp_line
			(start 0.12065 0.3048)
			(end 0.67945 0.3048)
			(stroke
				(width 0.1)
				(type default)
			)
			(layer "B.Fab")
		)
		(fp_line
			(start 0.67945 -0.305054)
			(end 0.12065 -0.305054)
			(stroke
				(width 0.1)
				(type default)
			)
			(layer "B.Fab")
		)
		(fp_line
			(start 0.67945 0.3048)
			(end 0.67945 -0.305054)
			(stroke
				(width 0.1)
				(type default)
			)
			(layer "B.Fab")
		)
		(pad "1" smd circle
			(at 0.40005 0 180)
			(size 0 0)
			(layers "B.Cu" "B.Mask" "B.Paste")
			(net "P3V3_AUX")
		)
		(pad "2" smd circle
			(at -0.40005 0 180)
			(size 0 0)
			(layers "B.Cu" "B.Mask" "B.Paste")
			(net "VCCIO0")
		)
	)
	(footprint ""
		(layer "B.Cu")
		(at 41.859454 -65.776094 -90)
		(property "Reference" "R194"
			(at 0 0 90)
			(layer "B.SilkS")
			(hide yes)
			(effects
				(font
					(size 1.27 1.27)
				)
				(justify mirror)
			)
		)
		(property "Value" ""
			(at 0 0 90)
			(layer "B.Fab")
			(effects
				(font
					(size 1.27 1.27)
				)
				(justify mirror)
			)
		)
		(duplicate_pad_numbers_are_jumpers no)
		(fp_line
			(start -0.7874 0.4064)
			(end 0.7874 0.4064)
			(stroke
				(width 0.1524)
				(type default)
			)
			(layer "B.SilkS")
		)
		(fp_line
			(start 0.7874 0.4064)
			(end 0.7874 -0.4064)
			(stroke
				(width 0.1524)
				(type default)
			)
			(layer "B.SilkS")
		)
		(fp_line
			(start -0.7874 -0.4064)
			(end -0.7874 0.4064)
			(stroke
				(width 0.1524)
				(type default)
			)
			(layer "B.SilkS")
		)
		(fp_line
			(start 0.7874 -0.4064)
			(end -0.7874 -0.4064)
			(stroke
				(width 0.1524)
				(type default)
			)
			(layer "B.SilkS")
		)
		(fp_line
			(start -0.67945 0.3048)
			(end -0.120396 0.3048)
			(stroke
				(width 0.1)
				(type default)
			)
			(layer "B.Fab")
		)
		(fp_line
			(start -0.120396 0.3048)
			(end -0.120396 0.2794)
			(stroke
				(width 0.1)
				(type default)
			)
			(layer "B.Fab")
		)
		(fp_line
			(start 0.12065 0.3048)
			(end 0.67945 0.3048)
			(stroke
				(width 0.1)
				(type default)
			)
			(layer "B.Fab")
		)
		(fp_line
			(start 0.67945 0.3048)
			(end 0.67945 -0.305054)
			(stroke
				(width 0.1)
				(type default)
			)
			(layer "B.Fab")
		)
		(fp_line
			(start -0.120396 0.2794)
			(end 0.12065 0.2794)
			(stroke
				(width 0.1)
				(type default)
			)
			(layer "B.Fab")
		)
		(fp_line
			(start 0.12065 0.2794)
			(end 0.12065 0.3048)
			(stroke
				(width 0.1)
				(type default)
			)
			(layer "B.Fab")
		)
		(fp_line
			(start -0.12065 -0.2794)
			(end -0.12065 -0.3048)
			(stroke
				(width 0.1)
				(type default)
			)
			(layer "B.Fab")
		)
		(fp_line
			(start 0.12065 -0.2794)
			(end -0.12065 -0.2794)
			(stroke
				(width 0.1)
				(type default)
			)
			(layer "B.Fab")
		)
		(fp_line
			(start -0.67945 -0.3048)
			(end -0.67945 0.3048)
			(stroke
				(width 0.1)
				(type default)
			)
			(layer "B.Fab")
		)
		(fp_line
			(start -0.12065 -0.3048)
			(end -0.67945 -0.3048)
			(stroke
				(width 0.1)
				(type default)
			)
			(layer "B.Fab")
		)
		(fp_line
			(start 0.12065 -0.305054)
			(end 0.12065 -0.2794)
			(stroke
				(width 0.1)
				(type default)
			)
			(layer "B.Fab")
		)
		(fp_line
			(start 0.67945 -0.305054)
			(end 0.12065 -0.305054)
			(stroke
				(width 0.1)
				(type default)
			)
			(layer "B.Fab")
		)
		(pad "1" smd circle
			(at 0.40005 0 90)
			(size 0 0)
			(layers "B.Cu" "B.Mask" "B.Paste")
			(net "P1V2_P1V0_I3C_VDDL1")
		)
		(pad "2" smd circle
			(at -0.40005 0 90)
			(size 0 0)
			(layers "B.Cu" "B.Mask" "B.Paste")
			(net "I3C1_SPD_SCL")
		)
	)
	(footprint ""
		(layer "B.Cu")
		(at 50.858674 -72.842374)
		(property "Reference" "R793"
			(at 0 0 0)
			(layer "B.SilkS")
			(hide yes)
			(effects
				(font
					(size 1.27 1.27)
				)
				(justify mirror)
			)
		)
		(property "Value" ""
			(at 0 0 0)
			(layer "B.Fab")
			(effects
				(font
					(size 1.27 1.27)
				)
				(justify mirror)
			)
		)
		(duplicate_pad_numbers_are_jumpers no)
		(fp_line
			(start -0.7874 -0.4064)
			(end -0.7874 0.4064)
			(stroke
				(width 0.1524)
				(type default)
			)
			(layer "B.SilkS")
		)
		(fp_line
			(start -0.7874 0.4064)
			(end 0.7874 0.4064)
			(stroke
				(width 0.1524)
				(type default)
			)
			(layer "B.SilkS")
		)
		(fp_line
			(start 0.7874 -0.4064)
			(end -0.7874 -0.4064)
			(stroke
				(width 0.1524)
				(type default)
			)
			(layer "B.SilkS")
		)
		(fp_line
			(start 0.7874 0.4064)
			(end 0.7874 -0.4064)
			(stroke
				(width 0.1524)
				(type default)
			)
			(layer "B.SilkS")
		)
		(fp_line
			(start -0.67945 -0.3048)
			(end -0.67945 0.3048)
			(stroke
				(width 0.1)
				(type default)
			)
			(layer "B.Fab")
		)
		(fp_line
			(start -0.67945 0.3048)
			(end -0.120396 0.3048)
			(stroke
				(width 0.1)
				(type default)
			)
			(layer "B.Fab")
		)
		(fp_line
			(start -0.12065 -0.3048)
			(end -0.67945 -0.3048)
			(stroke
				(width 0.1)
				(type default)
			)
			(layer "B.Fab")
		)
		(fp_line
			(start -0.12065 -0.2794)
			(end -0.12065 -0.3048)
			(stroke
				(width 0.1)
				(type default)
			)
			(layer "B.Fab")
		)
		(fp_line
			(start -0.120396 0.2794)
			(end 0.12065 0.2794)
			(stroke
				(width 0.1)
				(type default)
			)
			(layer "B.Fab")
		)
		(fp_line
			(start -0.120396 0.3048)
			(end -0.120396 0.2794)
			(stroke
				(width 0.1)
				(type default)
			)
			(layer "B.Fab")
		)
		(fp_line
			(start 0.12065 -0.305054)
			(end 0.12065 -0.2794)
			(stroke
				(width 0.1)
				(type default)
			)
			(layer "B.Fab")
		)
		(fp_line
			(start 0.12065 -0.2794)
			(end -0.12065 -0.2794)
			(stroke
				(width 0.1)
				(type default)
			)
			(layer "B.Fab")
		)
		(fp_line
			(start 0.12065 0.2794)
			(end 0.12065 0.3048)
			(stroke
				(width 0.1)
				(type default)
			)
			(layer "B.Fab")
		)
		(fp_line
			(start 0.12065 0.3048)
			(end 0.67945 0.3048)
			(stroke
				(width 0.1)
				(type default)
			)
			(layer "B.Fab")
		)
		(fp_line
			(start 0.67945 -0.305054)
			(end 0.12065 -0.305054)
			(stroke
				(width 0.1)
				(type default)
			)
			(layer "B.Fab")
		)
		(fp_line
			(start 0.67945 0.3048)
			(end 0.67945 -0.305054)
			(stroke
				(width 0.1)
				(type default)
			)
			(layer "B.Fab")
		)
		(pad "1" smd circle
			(at 0.40005 0 180)
			(size 0 0)
			(layers "B.Cu" "B.Mask" "B.Paste")
			(net "P1V8_AUX")
		)
		(pad "2" smd circle
			(at -0.40005 0 180)
			(size 0 0)
			(layers "B.Cu" "B.Mask" "B.Paste")
			(net "P1V8_SENSOR")
		)
	)
	(footprint ""
		(layer "B.Cu")
		(at 57.687464 -63.861696 90)
		(property "Reference" "R802"
			(at 0 0 90)
			(layer "B.SilkS")
			(hide yes)
			(effects
				(font
					(size 1.27 1.27)
				)
				(justify mirror)
			)
		)
		(property "Value" ""
			(at 0 0 90)
			(layer "B.Fab")
			(effects
				(font
					(size 1.27 1.27)
				)
				(justify mirror)
			)
		)
		(duplicate_pad_numbers_are_jumpers no)
		(fp_line
			(start 0.7874 -0.4064)
			(end -0.7874 -0.4064)
			(stroke
				(width 0.1524)
				(type default)
			)
			(layer "B.SilkS")
		)
		(fp_line
			(start -0.7874 -0.4064)
			(end -0.7874 0.4064)
			(stroke
				(width 0.1524)
				(type default)
			)
			(layer "B.SilkS")
		)
		(fp_line
			(start 0.7874 0.4064)
			(end 0.7874 -0.4064)
			(stroke
				(width 0.1524)
				(type default)
			)
			(layer "B.SilkS")
		)
		(fp_line
			(start -0.7874 0.4064)
			(end 0.7874 0.4064)
			(stroke
				(width 0.1524)
				(type default)
			)
			(layer "B.SilkS")
		)
		(fp_line
			(start 0.67945 -0.305054)
			(end 0.12065 -0.305054)
			(stroke
				(width 0.1)
				(type default)
			)
			(layer "B.Fab")
		)
		(fp_line
			(start 0.12065 -0.305054)
			(end 0.12065 -0.2794)
			(stroke
				(width 0.1)
				(type default)
			)
			(layer "B.Fab")
		)
		(fp_line
			(start -0.12065 -0.3048)
			(end -0.67945 -0.3048)
			(stroke
				(width 0.1)
				(type default)
			)
			(layer "B.Fab")
		)
		(fp_line
			(start -0.67945 -0.3048)
			(end -0.67945 0.3048)
			(stroke
				(width 0.1)
				(type default)
			)
			(layer "B.Fab")
		)
		(fp_line
			(start 0.12065 -0.2794)
			(end -0.12065 -0.2794)
			(stroke
				(width 0.1)
				(type default)
			)
			(layer "B.Fab")
		)
		(fp_line
			(start -0.12065 -0.2794)
			(end -0.12065 -0.3048)
			(stroke
				(width 0.1)
				(type default)
			)
			(layer "B.Fab")
		)
		(fp_line
			(start 0.12065 0.2794)
			(end 0.12065 0.3048)
			(stroke
				(width 0.1)
				(type default)
			)
			(layer "B.Fab")
		)
		(fp_line
			(start -0.120396 0.2794)
			(end 0.12065 0.2794)
			(stroke
				(width 0.1)
				(type default)
			)
			(layer "B.Fab")
		)
		(fp_line
			(start 0.67945 0.3048)
			(end 0.67945 -0.305054)
			(stroke
				(width 0.1)
				(type default)
			)
			(layer "B.Fab")
		)
		(fp_line
			(start 0.12065 0.3048)
			(end 0.67945 0.3048)
			(stroke
				(width 0.1)
				(type default)
			)
			(layer "B.Fab")
		)
		(fp_line
			(start -0.120396 0.3048)
			(end -0.120396 0.2794)
			(stroke
				(width 0.1)
				(type default)
			)
			(layer "B.Fab")
		)
		(fp_line
			(start -0.67945 0.3048)
			(end -0.120396 0.3048)
			(stroke
				(width 0.1)
				(type default)
			)
			(layer "B.Fab")
		)
		(pad "1" smd circle
			(at 0.40005 0 270)
			(size 0 0)
			(layers "B.Cu" "B.Mask" "B.Paste")
			(net "SPI_BMC_BOOT_CS1_R_N")
		)
		(pad "2" smd circle
			(at -0.40005 0 270)
			(size 0 0)
			(layers "B.Cu" "B.Mask" "B.Paste")
			(net "SPI_BMC_BOOT_CS1_R1_N")
		)
	)
	(footprint ""
		(layer "B.Cu")
		(at 70.104 -41.656 90)
		(property "Reference" "C225"
			(at 0 0 90)
			(layer "B.SilkS")
			(hide yes)
			(effects
				(font
					(size 1.27 1.27)
				)
				(justify mirror)
			)
		)
		(property "Value" ""
			(at 0 0 90)
			(layer "B.Fab")
			(effects
				(font
					(size 1.27 1.27)
				)
				(justify mirror)
			)
		)
		(duplicate_pad_numbers_are_jumpers no)
		(fp_line
			(start 0.7874 -0.4064)
			(end -0.7874 -0.4064)
			(stroke
				(width 0.1524)
				(type default)
			)
			(layer "B.SilkS")
		)
		(fp_line
			(start -0.7874 -0.4064)
			(end -0.7874 0.4064)
			(stroke
				(width 0.1524)
				(type default)
			)
			(layer "B.SilkS")
		)
		(fp_line
			(start 0.7874 0.4064)
			(end 0.7874 -0.4064)
			(stroke
				(width 0.1524)
				(type default)
			)
			(layer "B.SilkS")
		)
		(fp_line
			(start -0.7874 0.4064)
			(end 0.7874 0.4064)
			(stroke
				(width 0.1524)
				(type default)
			)
			(layer "B.SilkS")
		)
		(fp_line
			(start 0.67945 -0.305054)
			(end 0.12065 -0.305054)
			(stroke
				(width 0.1)
				(type default)
			)
			(layer "B.Fab")
		)
		(fp_line
			(start 0.12065 -0.305054)
			(end 0.12065 -0.2794)
			(stroke
				(width 0.1)
				(type default)
			)
			(layer "B.Fab")
		)
		(fp_line
			(start -0.12065 -0.3048)
			(end -0.67945 -0.3048)
			(stroke
				(width 0.1)
				(type default)
			)
			(layer "B.Fab")
		)
		(fp_line
			(start -0.67945 -0.3048)
			(end -0.67945 0.3048)
			(stroke
				(width 0.1)
				(type default)
			)
			(layer "B.Fab")
		)
		(fp_line
			(start 0.12065 -0.2794)
			(end -0.12065 -0.2794)
			(stroke
				(width 0.1)
				(type default)
			)
			(layer "B.Fab")
		)
		(fp_line
			(start -0.12065 -0.2794)
			(end -0.12065 -0.3048)
			(stroke
				(width 0.1)
				(type default)
			)
			(layer "B.Fab")
		)
		(fp_line
			(start 0.12065 0.2794)
			(end 0.12065 0.3048)
			(stroke
				(width 0.1)
				(type default)
			)
			(layer "B.Fab")
		)
		(fp_line
			(start -0.120396 0.2794)
			(end 0.12065 0.2794)
			(stroke
				(width 0.1)
				(type default)
			)
			(layer "B.Fab")
		)
		(fp_line
			(start 0.67945 0.3048)
			(end 0.67945 -0.305054)
			(stroke
				(width 0.1)
				(type default)
			)
			(layer "B.Fab")
		)
		(fp_line
			(start 0.12065 0.3048)
			(end 0.67945 0.3048)
			(stroke
				(width 0.1)
				(type default)
			)
			(layer "B.Fab")
		)
		(fp_line
			(start -0.120396 0.3048)
			(end -0.120396 0.2794)
			(stroke
				(width 0.1)
				(type default)
			)
			(layer "B.Fab")
		)
		(fp_line
			(start -0.67945 0.3048)
			(end -0.120396 0.3048)
			(stroke
				(width 0.1)
				(type default)
			)
			(layer "B.Fab")
		)
		(pad "1" smd circle
			(at 0.40005 0 270)
			(size 0 0)
			(layers "B.Cu" "B.Mask" "B.Paste")
			(net "P1V2_AUX")
		)
		(pad "2" smd circle
			(at -0.40005 0 270)
			(size 0 0)
			(layers "B.Cu" "B.Mask" "B.Paste")
			(net "GND")
		)
	)
)
